(kicad_pcb
	(version 20260206)
	(generator "pcbnew")
	(generator_version "10.0")
	(general
		(thickness 1.6)
		(legacy_teardrops no)
	)
	(paper "A4")
	(title_block
		(title "01162023_DA0F0TEBIF0_F0T_Expander_BD_F_brd_V02_OCP.brd")
		(comment 1 "Grand Teton / footprints 4583-4588 of 9728")
	)
	(layers
		(0 "F.Cu" signal "TOP")
		(4 "In1.Cu" signal "GND")
		(6 "In2.Cu" signal "VCC")
		(8 "In3.Cu" signal "VCC1")
		(10 "In4.Cu" signal "GND1")
		(12 "In5.Cu" signal "IN1")
		(14 "In6.Cu" signal "GND2")
		(16 "In7.Cu" signal "IN2")
		(18 "In8.Cu" signal "GND3")
		(20 "In9.Cu" signal "IN3")
		(22 "In10.Cu" signal "GND4")
		(24 "In11.Cu" signal "IN4")
		(26 "In12.Cu" signal "GND5")
		(28 "In13.Cu" signal "IN5")
		(30 "In14.Cu" signal "GND6")
		(32 "In15.Cu" signal "IN6")
		(34 "In16.Cu" signal "GND7")
		(2 "B.Cu" signal "BOTTOM")
		(9 "F.Adhes" user "F.Adhesive")
		(11 "B.Adhes" user "B.Adhesive")
		(13 "F.Paste" user "Package Geometry/Pastemask Top")
		(15 "B.Paste" user "Package Geometry/Pastemask Bottom")
		(5 "F.SilkS" user "Ref Des/Silkscreen Top")
		(7 "B.SilkS" user "Ref Des/Silkscreen Bottom")
		(1 "F.Mask" user "Board Geometry/Soldermask Top")
		(3 "B.Mask" user "Board Geometry/Soldermask Bottom")
		(17 "Dwgs.User" user "User.Drawings")
		(19 "Cmts.User" user "User.Comments")
		(21 "Eco1.User" user "User.Eco1")
		(23 "Eco2.User" user "User.Eco2")
		(25 "Edge.Cuts" user "Board Geometry/Outline")
		(27 "Margin" user)
		(31 "F.CrtYd" user "Package Geometry/Place Bound Top")
		(29 "B.CrtYd" user "Package Geometry/Place Bound Bottom")
		(35 "F.Fab" user "Ref Des/Assembly Top")
		(33 "B.Fab" user "Ref Des/Assembly Bottom")
	)
	(footprint ""
		(layer "F.Cu")
		(at 444.920116 -15.649956 180)
		(property "Reference" "H123"
			(at -1.310894 2.814066 0)
			(unlocked yes)
			(layer "B.SilkS")
			(effects
				(font
					(size 0.7874 0.5842)
					(thickness 0.1524)
				)
				(justify left mirror)
			)
		)
		(property "Value" ""
			(at 0 0 180)
			(layer "F.Fab")
			(effects
				(font
					(size 1.27 1.27)
				)
			)
		)
		(duplicate_pad_numbers_are_jumpers no)
		(pad "1" thru_hole rect
			(at 0 0 180)
			(size 4.2164 5.0038)
			(drill 2.0066
				(offset 0.099822 0)
			)
			(layers "*.Cu" "*.Mask")
			(remove_unused_layers no)
			(net "Net_8540")
			(clearance -0.8509)
			(padstack
				(mode front_inner_back)
				(layer "Inner"
					(shape circle)
					(size 4.0132 4.0132)
					(clearance -0.7493)
				)
				(layer "B.Cu"
					(shape circle)
					(size 4.0132 4.0132)
					(clearance -0.7493)
				)
			)
		)
	)
	(footprint ""
		(layer "F.Cu")
		(at 354.830888 -284.8991 180)
		(property "Reference" "PU14"
			(at -15.450058 -2.694178 90)
			(unlocked yes)
			(layer "F.SilkS")
			(effects
				(font
					(size 0.7874 0.5842)
					(thickness 0.1524)
				)
				(justify left)
			)
		)
		(property "Value" ""
			(at 0 0 180)
			(layer "F.Fab")
			(effects
				(font
					(size 1.27 1.27)
				)
			)
		)
		(duplicate_pad_numbers_are_jumpers no)
		(fp_line
			(start 2.500122 2.999994)
			(end 2.2987 2.999994)
			(stroke
				(width 0.1524)
				(type default)
			)
			(layer "F.SilkS")
		)
		(fp_line
			(start 2.500122 2.339594)
			(end 2.500122 2.999994)
			(stroke
				(width 0.1524)
				(type default)
			)
			(layer "F.SilkS")
		)
		(fp_line
			(start 2.500122 -2.999994)
			(end 2.500122 -2.44348)
			(stroke
				(width 0.1524)
				(type default)
			)
			(layer "F.SilkS")
		)
		(fp_line
			(start 2.31394 -2.999994)
			(end 2.500122 -2.999994)
			(stroke
				(width 0.1524)
				(type default)
			)
			(layer "F.SilkS")
		)
		(fp_line
			(start -2.2987 2.999994)
			(end -2.500122 2.999994)
			(stroke
				(width 0.1524)
				(type default)
			)
			(layer "F.SilkS")
		)
		(fp_line
			(start -2.500122 2.999994)
			(end -2.500122 2.339594)
			(stroke
				(width 0.1524)
				(type default)
			)
			(layer "F.SilkS")
		)
		(fp_line
			(start -2.500122 0.6604)
			(end -2.500122 0.229108)
			(stroke
				(width 0.1524)
				(type default)
			)
			(layer "F.SilkS")
		)
		(fp_line
			(start -2.500122 -2.529078)
			(end -2.500122 -2.999994)
			(stroke
				(width 0.1524)
				(type default)
			)
			(layer "F.SilkS")
		)
		(fp_line
			(start -2.500122 -2.999994)
			(end -2.24409 -2.999994)
			(stroke
				(width 0.1524)
				(type default)
			)
			(layer "F.SilkS")
		)
		(fp_poly
			(pts
				(xy -4.02336 -4.518406) (xy -4.741672 -3.79984) (xy -3.664204 -3.440684)
			)
			(stroke
				(width 0)
				(type default)
			)
			(fill yes)
			(layer "F.SilkS")
		)
		(fp_line
			(start 2.500122 2.999994)
			(end -2.500122 2.999994)
			(stroke
				(width 0.1)
				(type default)
			)
			(layer "F.Fab")
		)
		(fp_line
			(start 2.500122 -2.999994)
			(end 2.500122 2.999994)
			(stroke
				(width 0.1)
				(type default)
			)
			(layer "F.Fab")
		)
		(fp_line
			(start -2.500122 2.999994)
			(end -2.500122 -2.999994)
			(stroke
				(width 0.1)
				(type default)
			)
			(layer "F.Fab")
		)
		(fp_line
			(start -2.500122 -2.999994)
			(end 2.500122 -2.999994)
			(stroke
				(width 0.1)
				(type default)
			)
			(layer "F.Fab")
		)
		(fp_poly
			(pts
				(xy -4.218432 -2.783078) (xy -4.218432 -1.767078) (xy -3.202432 -2.275078)
			)
			(stroke
				(width 0)
				(type default)
			)
			(fill yes)
			(layer "F.Fab")
		)
		(pad "1" smd rect
			(at -2.400046 -2.275078 270)
			(size 0.2286 0.6096)
			(layers "F.Cu" "F.Mask" "F.Paste")
			(net "SW_P0V8_PEX3_VOS1")
		)
		(pad "2" smd rect
			(at -2.400046 -1.82499 270)
			(size 0.2286 0.6096)
			(layers "F.Cu" "F.Mask" "F.Paste")
			(net "GND")
		)
		(pad "3" smd rect
			(at -2.400046 -1.374902 270)
			(size 0.2286 0.6096)
			(layers "F.Cu" "F.Mask" "F.Paste")
			(net "P0V8_PEX3_VCC1")
		)
		(pad "4" smd rect
			(at -2.400046 -0.925068 270)
			(size 0.2286 0.6096)
			(layers "F.Cu" "F.Mask" "F.Paste")
			(net "P0V8_PEX3_PVCC")
		)
		(pad "5" smd rect
			(at -2.400046 -0.47498 270)
			(size 0.2286 0.6096)
			(layers "F.Cu" "F.Mask" "F.Paste")
			(net "GND")
		)
		(pad "6" smd rect
			(at -2.400046 -0.024892 270)
			(size 0.2286 0.6096)
			(layers "F.Cu" "F.Mask" "F.Paste")
			(net "NC_P0V8_PEX3_PH1_NC1")
		)
		(pad "7_9-20_24" smd circle
			(at 0 1.150112 270)
			(size 0 0)
			(layers "F.Cu" "F.Mask" "F.Paste")
			(net "GND")
		)
		(pad "10_19" smd rect
			(at 0 2.899918 270)
			(size 0.6096 4.318)
			(layers "F.Cu" "F.Mask" "F.Paste")
			(net "SW_P0V8_PEX3_PH1")
		)
		(pad "25_29" smd rect
			(at 1.549908 -1.279906 90)
			(size 2.0574 2.3114)
			(layers "F.Cu" "F.Mask" "F.Paste")
			(net "SW_P12V_P0V8_PEX3_FLT")
		)
		(pad "30" smd rect
			(at 2.05994 -2.899918 180)
			(size 0.2286 0.6096)
			(layers "F.Cu" "F.Mask" "F.Paste")
			(net "SW_P12V_P0V8_PEX3_FLT")
		)
		(pad "31" smd rect
			(at 1.610106 -2.899918 180)
			(size 0.2286 0.6096)
			(layers "F.Cu" "F.Mask" "F.Paste")
			(net "NC_P0V8_PEX3_PH1_NC3")
		)
		(pad "32" smd rect
			(at 1.160018 -2.899918 180)
			(size 0.2286 0.6096)
			(layers "F.Cu" "F.Mask" "F.Paste")
			(net "SW_P0V8_PEX3_PHASE1")
		)
		(pad "33" smd rect
			(at 0.70993 -2.899918 180)
			(size 0.2286 0.6096)
			(layers "F.Cu" "F.Mask" "F.Paste")
			(net "SW_P0V8_PEX3_BOOT1")
		)
		(pad "34" smd rect
			(at 0.260096 -2.899918 180)
			(size 0.2286 0.6096)
			(layers "F.Cu" "F.Mask" "F.Paste")
			(net "P0V8_PEX3_PWM1")
		)
		(pad "35" smd rect
			(at -0.189992 -2.899918 180)
			(size 0.2286 0.6096)
			(layers "F.Cu" "F.Mask" "F.Paste")
			(net "P0V8_PEX2_EN3")
		)
		(pad "36" smd rect
			(at -0.64008 -2.899918 180)
			(size 0.2286 0.6096)
			(layers "F.Cu" "F.Mask" "F.Paste")
			(net "P0V8_PEX3_TSEN")
		)
		(pad "37" smd rect
			(at -1.089914 -2.899918 180)
			(size 0.2286 0.6096)
			(layers "F.Cu" "F.Mask" "F.Paste")
			(net "P0V8_PEX3_LSET1")
		)
		(pad "38" smd rect
			(at -1.540002 -2.899918 180)
			(size 0.2286 0.6096)
			(layers "F.Cu" "F.Mask" "F.Paste")
			(net "P0V8_PEX3_ISEN1")
		)
		(pad "39" smd rect
			(at -1.99009 -2.899918 180)
			(size 0.2286 0.6096)
			(layers "F.Cu" "F.Mask" "F.Paste")
			(net "P0V8_PEX2_VREF")
		)
		(pad "40" smd rect
			(at -0.87503 -1.27508 180)
			(size 1.7526 1.9558)
			(layers "F.Cu" "F.Mask" "F.Paste")
			(net "GND")
		)
		(pad "41" smd rect
			(at -1.525016 0.249936 90)
			(size 0.3048 0.4572)
			(layers "F.Cu" "F.Mask" "F.Paste")
			(net "NC_P0V8_PEX3_PH1_NC2")
		)
		(zone
			(layer "F.Cu")
			(hatch none 0.5)
			(connect_pads
				(clearance 0)
			)
			(min_thickness 0.25)
			(keepout
				(tracks not_allowed)
				(vias allowed)
				(pads allowed)
				(copperpour not_allowed)
				(footprints allowed)
			)
			(placement
				(enabled no)
				(sheetname "")
			)
			(fill
				(thermal_gap 0.5)
				(thermal_bridge_width 0.5)
				(island_removal_mode 0)
			)
			(polygon
				(pts
					(xy 357.33101 -287.899094) (xy 357.33101 -287.149794) (xy 352.330766 -287.149794) (xy 352.330766 -287.899094)
					(xy 352.621088 -287.899094) (xy 352.621088 -287.443418) (xy 357.040688 -287.443418) (xy 357.040688 -287.899094)
				)
			)
		)
	)
	(footprint ""
		(layer "F.Cu")
		(at 152.634442 -250.070874 -90)
		(property "Reference" "R1275"
			(at 0 0 270)
			(layer "F.SilkS")
			(hide yes)
			(effects
				(font
					(size 1.27 1.27)
				)
			)
		)
		(property "Value" ""
			(at 0 0 270)
			(layer "F.Fab")
			(effects
				(font
					(size 1.27 1.27)
				)
			)
		)
		(duplicate_pad_numbers_are_jumpers no)
		(fp_line
			(start -0.7874 0.4064)
			(end -0.7874 -0.4064)
			(stroke
				(width 0.1524)
				(type default)
			)
			(layer "F.SilkS")
		)
		(fp_line
			(start 0.7874 0.4064)
			(end -0.7874 0.4064)
			(stroke
				(width 0.1524)
				(type default)
			)
			(layer "F.SilkS")
		)
		(fp_line
			(start -0.7874 -0.4064)
			(end 0.7874 -0.4064)
			(stroke
				(width 0.1524)
				(type default)
			)
			(layer "F.SilkS")
		)
		(fp_line
			(start 0.7874 -0.4064)
			(end 0.7874 0.4064)
			(stroke
				(width 0.1524)
				(type default)
			)
			(layer "F.SilkS")
		)
		(fp_line
			(start -0.67945 0.3048)
			(end -0.67945 -0.305054)
			(stroke
				(width 0.1)
				(type default)
			)
			(layer "F.Fab")
		)
		(fp_line
			(start -0.12065 0.3048)
			(end -0.67945 0.3048)
			(stroke
				(width 0.1)
				(type default)
			)
			(layer "F.Fab")
		)
		(fp_line
			(start 0.120396 0.3048)
			(end 0.120396 0.2794)
			(stroke
				(width 0.1)
				(type default)
			)
			(layer "F.Fab")
		)
		(fp_line
			(start 0.67945 0.3048)
			(end 0.120396 0.3048)
			(stroke
				(width 0.1)
				(type default)
			)
			(layer "F.Fab")
		)
		(fp_line
			(start -0.12065 0.2794)
			(end -0.12065 0.3048)
			(stroke
				(width 0.1)
				(type default)
			)
			(layer "F.Fab")
		)
		(fp_line
			(start 0.120396 0.2794)
			(end -0.12065 0.2794)
			(stroke
				(width 0.1)
				(type default)
			)
			(layer "F.Fab")
		)
		(fp_line
			(start -0.12065 -0.2794)
			(end 0.12065 -0.2794)
			(stroke
				(width 0.1)
				(type default)
			)
			(layer "F.Fab")
		)
		(fp_line
			(start 0.12065 -0.2794)
			(end 0.12065 -0.3048)
			(stroke
				(width 0.1)
				(type default)
			)
			(layer "F.Fab")
		)
		(fp_line
			(start 0.12065 -0.3048)
			(end 0.67945 -0.3048)
			(stroke
				(width 0.1)
				(type default)
			)
			(layer "F.Fab")
		)
		(fp_line
			(start 0.67945 -0.3048)
			(end 0.67945 0.3048)
			(stroke
				(width 0.1)
				(type default)
			)
			(layer "F.Fab")
		)
		(fp_line
			(start -0.67945 -0.305054)
			(end -0.12065 -0.305054)
			(stroke
				(width 0.1)
				(type default)
			)
			(layer "F.Fab")
		)
		(fp_line
			(start -0.12065 -0.305054)
			(end -0.12065 -0.2794)
			(stroke
				(width 0.1)
				(type default)
			)
			(layer "F.Fab")
		)
		(pad "1" smd circle
			(at -0.40005 0 270)
			(size 0 0)
			(layers "F.Cu" "F.Mask" "F.Paste")
			(net "PEX1_MODE_SEL6")
		)
		(pad "2" smd circle
			(at 0.40005 0 270)
			(size 0 0)
			(layers "F.Cu" "F.Mask" "F.Paste")
			(net "P1V8_PEX")
		)
	)
	(footprint ""
		(layer "F.Cu")
		(at 228.494082 -273.064732 90)
		(property "Reference" "C4281"
			(at 0 0 90)
			(layer "F.SilkS")
			(hide yes)
			(effects
				(font
					(size 1.27 1.27)
				)
			)
		)
		(property "Value" ""
			(at 0 0 90)
			(layer "F.Fab")
			(effects
				(font
					(size 1.27 1.27)
				)
			)
		)
		(duplicate_pad_numbers_are_jumpers no)
		(fp_line
			(start 0.299974 -0.150114)
			(end 0.299974 0.150114)
			(stroke
				(width 0.1)
				(type default)
			)
			(layer "F.Fab")
		)
		(fp_line
			(start -0.299974 -0.150114)
			(end 0.299974 -0.150114)
			(stroke
				(width 0.1)
				(type default)
			)
			(layer "F.Fab")
		)
		(fp_line
			(start 0.299974 0.150114)
			(end -0.299974 0.150114)
			(stroke
				(width 0.1)
				(type default)
			)
			(layer "F.Fab")
		)
		(fp_line
			(start -0.299974 0.150114)
			(end -0.299974 -0.150114)
			(stroke
				(width 0.1)
				(type default)
			)
			(layer "F.Fab")
		)
		(pad "1" smd rect
			(at -0.2667 0 90)
			(size 0.3048 0.381)
			(layers "F.Cu" "F.Mask" "F.Paste")
			(net "P1V25_SERDES_VDDPLL_PEX1")
		)
		(pad "2" smd rect
			(at 0.2667 0 90)
			(size 0.3048 0.381)
			(layers "F.Cu" "F.Mask" "F.Paste")
			(net "GND")
		)
	)
	(footprint ""
		(layer "F.Cu")
		(at 193.16446 -29.079952 180)
		(property "Reference" "R6204"
			(at 0 0 180)
			(layer "F.SilkS")
			(hide yes)
			(effects
				(font
					(size 1.27 1.27)
				)
			)
		)
		(property "Value" ""
			(at 0 0 180)
			(layer "F.Fab")
			(effects
				(font
					(size 1.27 1.27)
				)
			)
		)
		(duplicate_pad_numbers_are_jumpers no)
		(fp_line
			(start 0.7874 0.4064)
			(end -0.7874 0.4064)
			(stroke
				(width 0.1524)
				(type default)
			)
			(layer "F.SilkS")
		)
		(fp_line
			(start 0.7874 -0.4064)
			(end 0.7874 0.4064)
			(stroke
				(width 0.1524)
				(type default)
			)
			(layer "F.SilkS")
		)
		(fp_line
			(start -0.7874 0.4064)
			(end -0.7874 -0.4064)
			(stroke
				(width 0.1524)
				(type default)
			)
			(layer "F.SilkS")
		)
		(fp_line
			(start -0.7874 -0.4064)
			(end 0.7874 -0.4064)
			(stroke
				(width 0.1524)
				(type default)
			)
			(layer "F.SilkS")
		)
		(fp_line
			(start 0.67945 0.3048)
			(end 0.120396 0.3048)
			(stroke
				(width 0.1)
				(type default)
			)
			(layer "F.Fab")
		)
		(fp_line
			(start 0.67945 -0.3048)
			(end 0.67945 0.3048)
			(stroke
				(width 0.1)
				(type default)
			)
			(layer "F.Fab")
		)
		(fp_line
			(start 0.12065 -0.2794)
			(end 0.12065 -0.3048)
			(stroke
				(width 0.1)
				(type default)
			)
			(layer "F.Fab")
		)
		(fp_line
			(start 0.12065 -0.3048)
			(end 0.67945 -0.3048)
			(stroke
				(width 0.1)
				(type default)
			)
			(layer "F.Fab")
		)
		(fp_line
			(start 0.120396 0.3048)
			(end 0.120396 0.2794)
			(stroke
				(width 0.1)
				(type default)
			)
			(layer "F.Fab")
		)
		(fp_line
			(start 0.120396 0.2794)
			(end -0.12065 0.2794)
			(stroke
				(width 0.1)
				(type default)
			)
			(layer "F.Fab")
		)
		(fp_line
			(start -0.12065 0.3048)
			(end -0.67945 0.3048)
			(stroke
				(width 0.1)
				(type default)
			)
			(layer "F.Fab")
		)
		(fp_line
			(start -0.12065 0.2794)
			(end -0.12065 0.3048)
			(stroke
				(width 0.1)
				(type default)
			)
			(layer "F.Fab")
		)
		(fp_line
			(start -0.12065 -0.2794)
			(end 0.12065 -0.2794)
			(stroke
				(width 0.1)
				(type default)
			)
			(layer "F.Fab")
		)
		(fp_line
			(start -0.12065 -0.305054)
			(end -0.12065 -0.2794)
			(stroke
				(width 0.1)
				(type default)
			)
			(layer "F.Fab")
		)
		(fp_line
			(start -0.67945 0.3048)
			(end -0.67945 -0.305054)
			(stroke
				(width 0.1)
				(type default)
			)
			(layer "F.Fab")
		)
		(fp_line
			(start -0.67945 -0.305054)
			(end -0.12065 -0.305054)
			(stroke
				(width 0.1)
				(type default)
			)
			(layer "F.Fab")
		)
		(pad "1" smd circle
			(at -0.40005 0 180)
			(size 0 0)
			(layers "F.Cu" "F.Mask" "F.Paste")
			(net "GND")
		)
		(pad "2" smd circle
			(at 0.40005 0 180)
			(size 0 0)
			(layers "F.Cu" "F.Mask" "F.Paste")
			(net "SSD6_PWRDIS_R")
		)
	)
	(footprint ""
		(layer "F.Cu")
		(at 17.622774 -22.867366 90)
		(property "Reference" "C3878"
			(at 0 0 90)
			(layer "F.SilkS")
			(hide yes)
			(effects
				(font
					(size 1.27 1.27)
				)
			)
		)
		(property "Value" ""
			(at 0 0 90)
			(layer "F.Fab")
			(effects
				(font
					(size 1.27 1.27)
				)
			)
		)
		(duplicate_pad_numbers_are_jumpers no)
		(fp_line
			(start 0.7874 -0.4064)
			(end 0.7874 0.4064)
			(stroke
				(width 0.1524)
				(type default)
			)
			(layer "F.SilkS")
		)
		(fp_line
			(start -0.7874 -0.4064)
			(end 0.7874 -0.4064)
			(stroke
				(width 0.1524)
				(type default)
			)
			(layer "F.SilkS")
		)
		(fp_line
			(start 0.7874 0.4064)
			(end -0.7874 0.4064)
			(stroke
				(width 0.1524)
				(type default)
			)
			(layer "F.SilkS")
		)
		(fp_line
			(start -0.7874 0.4064)
			(end -0.7874 -0.4064)
			(stroke
				(width 0.1524)
				(type default)
			)
			(layer "F.SilkS")
		)
		(fp_line
			(start -0.12065 -0.305054)
			(end -0.12065 -0.2794)
			(stroke
				(width 0.1)
				(type default)
			)
			(layer "F.Fab")
		)
		(fp_line
			(start -0.67945 -0.305054)
			(end -0.12065 -0.305054)
			(stroke
				(width 0.1)
				(type default)
			)
			(layer "F.Fab")
		)
		(fp_line
			(start 0.67945 -0.3048)
			(end 0.67945 0.3048)
			(stroke
				(width 0.1)
				(type default)
			)
			(layer "F.Fab")
		)
		(fp_line
			(start 0.12065 -0.3048)
			(end 0.67945 -0.3048)
			(stroke
				(width 0.1)
				(type default)
			)
			(layer "F.Fab")
		)
		(fp_line
			(start 0.12065 -0.2794)
			(end 0.12065 -0.3048)
			(stroke
				(width 0.1)
				(type default)
			)
			(layer "F.Fab")
		)
		(fp_line
			(start -0.12065 -0.2794)
			(end 0.12065 -0.2794)
			(stroke
				(width 0.1)
				(type default)
			)
			(layer "F.Fab")
		)
		(fp_line
			(start 0.120396 0.2794)
			(end -0.12065 0.2794)
			(stroke
				(width 0.1)
				(type default)
			)
			(layer "F.Fab")
		)
		(fp_line
			(start -0.12065 0.2794)
			(end -0.12065 0.3048)
			(stroke
				(width 0.1)
				(type default)
			)
			(layer "F.Fab")
		)
		(fp_line
			(start 0.67945 0.3048)
			(end 0.120396 0.3048)
			(stroke
				(width 0.1)
				(type default)
			)
			(layer "F.Fab")
		)
		(fp_line
			(start 0.120396 0.3048)
			(end 0.120396 0.2794)
			(stroke
				(width 0.1)
				(type default)
			)
			(layer "F.Fab")
		)
		(fp_line
			(start -0.12065 0.3048)
			(end -0.67945 0.3048)
			(stroke
				(width 0.1)
				(type default)
			)
			(layer "F.Fab")
		)
		(fp_line
			(start -0.67945 0.3048)
			(end -0.67945 -0.305054)
			(stroke
				(width 0.1)
				(type default)
			)
			(layer "F.Fab")
		)
		(pad "1" smd circle
			(at -0.40005 0 90)
			(size 0 0)
			(layers "F.Cu" "F.Mask" "F.Paste")
			(net "P12V_SSD0")
		)
		(pad "2" smd circle
			(at 0.40005 0 90)
			(size 0 0)
			(layers "F.Cu" "F.Mask" "F.Paste")
			(net "GND")
		)
	)
)
